FILE_TYPE = CONNECTIVITY;
{Allegro Design Entry HDL 16.6-p007 (v16-6-112F) 10/10/2012}
"PAGE_NUMBER" = 40;
0"NC";
1"GND\g";
2"GND\g";
3"GND\g";
4"GND\g";
5"GND\g";
6"GND\g";
7"GND\g";
8"GND\g";
%"GND"
"1","(-2625,450)","0","mstr_symbols","I11";
;
HDL_POWER"GND"
BODY_TYPE"PLUMBING"
CDS_LIB"mstr_symbols"
SIZE"1B"
VOLTAGE"0.0V";
"A\NAC"1;
%"GND"
"1","(-775,450)","0","mstr_symbols","I13";
;
HDL_POWER"GND"
BODY_TYPE"PLUMBING"
SIZE"1B"
CDS_LIB"mstr_symbols"
VOLTAGE"0.0V";
"A\NAC"2;
%"GND"
"1","(-2325,475)","0","mstr_symbols","I14";
;
HDL_POWER"GND"
BODY_TYPE"PLUMBING"
SIZE"1B"
CDS_LIB"mstr_symbols"
VOLTAGE"0.0V";
"A\NAC"3;
%"SKX_EXT_B"
"23","(-7050,2575)","0","chpset_lib","I20";
;
CDS_SEC"23"
ROOM"CPU0"
CDS_LOCATION"U5D1"
SEC"23"
CDS_LIB"chpset_lib"
SEC_TYPE"BGA1"
PACK_TYPE"BGA1"
MATERIAL"IC"
PART_NUMBER"TBD"
LOCATION"U5D1";
"VSS<1094>"
$PN"J74"6;
"VSS<1095>"
$PN"J72"6;
"VSS<1096>"
$PN"J40"6;
"VSS<1097>"
$PN"J38"6;
"VSS<1098>"
$PN"J34"6;
"VSS<1099>"
$PN"J32"6;
"VSS<1100>"
$PN"J28"6;
"VSS<1101>"
$PN"J26"6;
"VSS<1102>"
$PN"J22"6;
"VSS<1103>"
$PN"J14"6;
"VSS<1104>"
$PN"J12"6;
"VSS<1105>"
$PN"J4"6;
"VSS<1106>"
$PN"DN44"6;
"VSS<1107>"
$PN"H75"6;
"VSS<1108>"
$PN"H71"6;
"VSS<1109>"
$PN"H65"6;
"VSS<1110>"
$PN"H41"6;
"VSS<1111>"
$PN"H39"6;
"VSS<1112>"
$PN"H37"6;
"VSS<1113>"
$PN"H35"6;
"VSS<1114>"
$PN"H33"6;
"VSS<1115>"
$PN"H31"6;
"VSS<1116>"
$PN"H29"6;
"VSS<1117>"
$PN"H27"6;
"VSS<1118>"
$PN"H25"6;
"VSS<1119>"
$PN"H11"6;
"VSS<1120>"
$PN"H3"6;
"VSS<1121>"
$PN"G82"6;
"VSS<1122>"
$PN"G80"6;
"VSS<1123>"
$PN"G78"6;
"VSS<1124>"
$PN"G76"6;
"VSS<1125>"
$PN"G70"6;
"VSS<1126>"
$PN"G66"6;
"VSS<1127>"
$PN"G42"6;
"VSS<1128>"
$PN"G38"6;
"VSS<1129>"
$PN"G36"6;
"VSS<1130>"
$PN"G32"6;
"VSS<1131>"
$PN"G30"6;
"VSS<1132>"
$PN"G26"6;
"VSS<1133>"
$PN"G24"6;
"VSS<1134>"
$PN"G22"6;
"VSS<1135>"
$PN"G8"6;
"VSS<1136>"
$PN"G4"6;
"VSS<1137>"
$PN"F69"6;
"VSS<1138>"
$PN"F67"6;
"VSS<1139>"
$PN"F43"6;
"VSS<1140>"
$PN"F37"6;
"VSS<1141>"
$PN"F31"6;
"VSS<1142>"
$PN"F25"6;
"VSS<1143>"
$PN"F19"6;
"VSS<1144>"
$PN"F17"6;
"VSS<1145>"
$PN"F5"6;
"VSS<1146>"
$PN"E76"6;
"VSS<1147>"
$PN"E74"6;
"VSS<1148>"
$PN"E72"6;
"VSS<1149>"
$PN"E22"6;
"VSS<1150>"
$PN"E20"6;
"VSS<1151>"
$PN"E18"6;
"VSS<1152>"
$PN"E16"6;
"VSS<1153>"
$PN"E8"6;
"VSS<1154>"
$PN"E6"6;
"VSS<1155>"
$PN"D77"6;
"VSS<1156>"
$PN"D43"6;
"VSS<1157>"
$PN"D41"6;
"VSS<1158>"
$PN"D39"6;
"VSS<1159>"
$PN"D37"6;
"VSS<1160>"
$PN"D35"6;
"VSS<1161>"
$PN"D33"6;
"VSS<1162>"
$PN"D31"6;
"VSS<1163>"
$PN"D29"6;
"VSS<1164>"
$PN"D27"6;
"VSS<1165>"
$PN"D25"6;
"VSS<1166>"
$PN"D13"6;
"VSS<1167>"
$PN"D11"6;
"VSS<1168>"
$PN"CM27"6;
"VSS<1169>"
$PN"C78"6;
"VSS<1170>"
$PN"C76"6;
"VSS<1171>"
$PN"C16"6;
"VSS<1172>"
$PN"C14"6;
"VSS<1173>"
$PN"C12"6;
"VSS<1174>"
$PN"C10"4;
"VSS<1175>"
$PN"C8"4;
"VSS<1176>"
$PN"B75"4;
"VSS<1177>"
$PN"B71"4;
"VSS<1178>"
$PN"B37"4;
"VSS<1179>"
$PN"B31"4;
"VSS<1180>"
$PN"B25"4;
"VSS<1181>"
$PN"A38"4;
"VSS<1182>"
$PN"A36"4;
"VSS<1183>"
$PN"A32"4;
"VSS<1184>"
$PN"A30"4;
"VSS<1185>"
$PN"A26"4;
"VSS<1186>"
$PN"AC58"4;
"VSS<1187>"
$PN"AC60"4;
"VSS<1188>"
$PN"AC62"4;
"VSS<1189>"
$PN"AJ4"4;
"VSS<1190>"
$PN"AR6"4;
"VSS<1191>"
$PN"CG6"4;
"VSS<1192>"
$PN"CW6"4;
"VSS<1193>"
$PN"DE48"4;
"VSS<1194>"
$PN"DE50"4;
"VSS<1195>"
$PN"DE52"4;
"VSS<1196>"
$PN"DE54"4;
"VSS<1197>"
$PN"DE56"4;
"VSS<1198>"
$PN"DE58"4;
"VSS<1199>"
$PN"DE60"4;
"VSS<1200>"
$PN"DE62"4;
"VSS<1201>"
$PN"DL8"4;
"VSS<1202>"
$PN"DN18"4;
"VSS<1203>"
$PN"DP45"4;
"VSS<1204>"
$PN"DP47"4;
"VSS<1205>"
$PN"DP49"4;
"VSS<1206>"
$PN"DP51"4;
"VSS<1207>"
$PN"DP53"4;
"VSS<1208>"
$PN"DP55"4;
"VSS<1209>"
$PN"DP57"4;
"VSS<1210>"
$PN"DP59"4;
"VSS<1211>"
$PN"DP61"4;
"VSS<1212>"
$PN"DP63"4;
"VSS<1213>"
$PN"DP9"4;
"VSS<1214>"
$PN"DV19"4;
"VSS<1215>"
$PN"DY45"4;
"VSS<1216>"
$PN"DY47"4;
"VSS<1217>"
$PN"DY49"4;
"VSS<1218>"
$PN"DY51"4;
"VSS<1219>"
$PN"DY53"4;
"VSS<1220>"
$PN"DY55"4;
"VSS<1221>"
$PN"DY57"4;
"VSS<1222>"
$PN"DY59"4;
"VSS<1223>"
$PN"DY61"4;
"VSS<1224>"
$PN"DY63"4;
"VSS<1225>"
$PN"EA14"4;
"VSS<1226>"
$PN"L8"4;
"VSS<1227>"
$PN"V11"4;
"VSS<1228>"
$PN"E66"4;
"VSS<1229>"
$PN"ED69"4;
"VSS<1230>"
$PN"EE80"4;
"VSS<1231>"
$PN"EE8"4;
"VSS<1232>"
$PN"EE40"4;
"VSS<1233>"
$PN"ED81"4;
"VSS<1234>"
$PN"ED7"4;
"VSS<1235>"
$PN"ED41"4;
"VSS<1236>"
$PN"EC82"4;
"VSS<1237>"
$PN"EC6"4;
"VSS<1238>"
$PN"EC42"4;
"VSS<1239>"
$PN"DW2"4;
"VSS<1240>"
$PN"EB83"4;
"VSS<1241>"
$PN"EA84"4;
"VSS<1242>"
$PN"DY85"4;
"VSS<1243>"
$PN"J86"4;
"VSS<1244>"
$PN"E82"4;
"VSS<1245>"
$PN"D81"4;
"VSS<1246>"
$PN"D3"4;
"VSS<1247>"
$PN"C80"4;
"VSS<1248>"
$PN"C4"4;
"VSS<1249>"
$PN"B79"4;
"VSS<1250>"
$PN"B5"4;
"VSS<1251>"
$PN"B43"4;
"VSS<1252>"
$PN"A42"4;
"VSS<1253>"
$PN"B9"4;
%"SKX_EXT_B"
"24","(-5225,2575)","0","chpset_lib","I21";
;
CDS_SEC"24"
ROOM"CPU0"
CDS_LOCATION"U5D1"
SEC"24"
CDS_LIB"chpset_lib"
SEC_TYPE"BGA1"
PACK_TYPE"BGA1"
MATERIAL"IC"
PART_NUMBER"TBD"
LOCATION"U5D1";
"VSS<934>"
$PN"AA16"7;
"VSS<935>"
$PN"AA4"7;
"VSS<936>"
$PN"Y85"7;
"VSS<937>"
$PN"Y83"7;
"VSS<938>"
$PN"Y81"7;
"VSS<939>"
$PN"Y79"7;
"VSS<940>"
$PN"Y73"7;
"VSS<941>"
$PN"Y71"7;
"VSS<942>"
$PN"Y9"7;
"VSS<943>"
$PN"Y7"7;
"VSS<944>"
$PN"Y67"7;
"VSS<945>"
$PN"Y5"7;
"VSS<946>"
$PN"Y17"7;
"VSS<947>"
$PN"Y15"7;
"VSS<948>"
$PN"W82"7;
"VSS<949>"
$PN"W78"7;
"VSS<950>"
$PN"W74"7;
"VSS<951>"
$PN"W68"7;
"VSS<952>"
$PN"W42"7;
"VSS<953>"
$PN"W40"7;
"VSS<954>"
$PN"W38"7;
"VSS<955>"
$PN"W36"7;
"VSS<956>"
$PN"W34"7;
"VSS<957>"
$PN"W32"7;
"VSS<958>"
$PN"W30"7;
"VSS<959>"
$PN"W28"7;
"VSS<960>"
$PN"W26"7;
"VSS<961>"
$PN"W24"7;
"VSS<962>"
$PN"W22"7;
"VSS<963>"
$PN"W12"7;
"VSS<964>"
$PN"AC56"7;
"VSS<965>"
$PN"W8"7;
"VSS<966>"
$PN"V83"7;
"VSS<967>"
$PN"V77"7;
"VSS<968>"
$PN"V75"7;
"VSS<969>"
$PN"V73"7;
"VSS<970>"
$PN"V43"7;
"VSS<971>"
$PN"V23"7;
"VSS<972>"
$PN"V21"7;
"VSS<973>"
$PN"V15"7;
"VSS<974>"
$PN"V13"7;
"VSS<975>"
$PN"V9"7;
"VSS<976>"
$PN"V5"7;
"VSS<977>"
$PN"V1"7;
"VSS<978>"
$PN"U86"7;
"VSS<979>"
$PN"U80"7;
"VSS<980>"
$PN"U78"7;
"VSS<981>"
$PN"U76"7;
"VSS<982>"
$PN"U74"7;
"VSS<983>"
$PN"U70"7;
"VSS<984>"
$PN"U68"7;
"VSS<985>"
$PN"U42"7;
"VSS<986>"
$PN"U36"7;
"VSS<987>"
$PN"U30"7;
"VSS<988>"
$PN"U24"7;
"VSS<989>"
$PN"U22"7;
"VSS<990>"
$PN"U20"7;
"VSS<991>"
$PN"U6"7;
"VSS<992>"
$PN"U4"7;
"VSS<993>"
$PN"U2"7;
"VSS<994>"
$PN"T85"7;
"VSS<995>"
$PN"T83"7;
"VSS<996>"
$PN"T77"7;
"VSS<997>"
$PN"T73"7;
"VSS<998>"
$PN"T65"7;
"VSS<999>"
$PN"T41"7;
"VSS<1000>"
$PN"T37"7;
"VSS<1001>"
$PN"T35"7;
"VSS<1002>"
$PN"T31"7;
"VSS<1003>"
$PN"T29"7;
"VSS<1004>"
$PN"T25"7;
"VSS<1005>"
$PN"T17"7;
"VSS<1006>"
$PN"T13"7;
"VSS<1007>"
$PN"R86"7;
"VSS<1008>"
$PN"R78"7;
"VSS<1009>"
$PN"R72"7;
"VSS<1010>"
$PN"R68"7;
"VSS<1011>"
$PN"R40"7;
"VSS<1012>"
$PN"R38"7;
"VSS<1013>"
$PN"R34"7;
"VSS<1014>"
$PN"R32"5;
"VSS<1015>"
$PN"R28"5;
"VSS<1016>"
$PN"R26"5;
"VSS<1017>"
$PN"R22"5;
"VSS<1018>"
$PN"R4"5;
"VSS<1019>"
$PN"R2"5;
"VSS<1020>"
$PN"R18"5;
"VSS<1021>"
$PN"R14"5;
"VSS<1022>"
$PN"P83"5;
"VSS<1023>"
$PN"P81"5;
"VSS<1024>"
$PN"P71"5;
"VSS<1025>"
$PN"P69"5;
"VSS<1026>"
$PN"P67"5;
"VSS<1027>"
$PN"P39"5;
"VSS<1028>"
$PN"P33"5;
"VSS<1029>"
$PN"P27"5;
"VSS<1030>"
$PN"P15"5;
"VSS<1031>"
$PN"P11"5;
"VSS<1032>"
$PN"N8"5;
"VSS<1033>"
$PN"N4"5;
"VSS<1034>"
$PN"N78"5;
"VSS<1035>"
$PN"N76"5;
"VSS<1036>"
$PN"N74"5;
"VSS<1037>"
$PN"N72"5;
"VSS<1038>"
$PN"N70"5;
"VSS<1039>"
$PN"N66"5;
"VSS<1040>"
$PN"N6"5;
"VSS<1041>"
$PN"N22"5;
"VSS<1042>"
$PN"N20"5;
"VSS<1043>"
$PN"DM19"5;
"VSS<1044>"
$PN"M85"5;
"VSS<1045>"
$PN"M83"5;
"VSS<1046>"
$PN"M79"5;
"VSS<1047>"
$PN"M71"5;
"VSS<1048>"
$PN"M65"5;
"VSS<1049>"
$PN"M43"5;
"VSS<1050>"
$PN"M41"5;
"VSS<1051>"
$PN"M39"5;
"VSS<1052>"
$PN"M37"5;
"VSS<1053>"
$PN"M35"5;
"VSS<1054>"
$PN"M33"5;
"VSS<1055>"
$PN"M31"5;
"VSS<1056>"
$PN"M29"5;
"VSS<1057>"
$PN"M27"5;
"VSS<1058>"
$PN"M25"5;
"VSS<1059>"
$PN"M23"5;
"VSS<1060>"
$PN"M19"5;
"VSS<1061>"
$PN"M17"5;
"VSS<1062>"
$PN"M15"5;
"VSS<1063>"
$PN"CT7"5;
"VSS<1064>"
$PN"BT9"5;
"VSS<1065>"
$PN"L82"5;
"VSS<1066>"
$PN"L80"5;
"VSS<1067>"
$PN"L78"5;
"VSS<1068>"
$PN"L72"5;
"VSS<1069>"
$PN"L22"5;
"VSS<1070>"
$PN"L20"5;
"VSS<1071>"
$PN"L6"5;
"VSS<1072>"
$PN"L2"5;
"VSS<1073>"
$PN"L10"5;
"VSS<1074>"
$PN"K85"5;
"VSS<1075>"
$PN"K83"5;
"VSS<1076>"
$PN"K81"5;
"VSS<1077>"
$PN"K77"5;
"VSS<1078>"
$PN"K73"5;
"VSS<1079>"
$PN"K71"5;
"VSS<1080>"
$PN"K69"5;
"VSS<1081>"
$PN"K67"5;
"VSS<1082>"
$PN"K65"5;
"VSS<1083>"
$PN"K39"5;
"VSS<1084>"
$PN"K33"5;
"VSS<1085>"
$PN"K27"5;
"VSS<1086>"
$PN"DB7"5;
"VSS<1087>"
$PN"K17"5;
"VSS<1088>"
$PN"K13"5;
"VSS<1089>"
$PN"K11"5;
"VSS<1090>"
$PN"K1"5;
"VSS<1091>"
$PN"J84"5;
"VSS<1092>"
$PN"J82"5;
"VSS<1093>"
$PN"J76"5;
%"SKX_EXT_B"
"25","(-3400,2575)","0","chpset_lib","I22";
;
CDS_SEC"25"
ROOM"CPU0"
CDS_LOCATION"U5D1"
SEC"25"
CDS_LIB"chpset_lib"
SEC_TYPE"BGA1"
PACK_TYPE"BGA1"
MATERIAL"IC"
PART_NUMBER"TBD"
LOCATION"U5D1";
"VSS<774>"
$PN"AL68"1;
"VSS<775>"
$PN"AL64"1;
"VSS<776>"
$PN"AL56"1;
"VSS<777>"
$PN"AL32"1;
"VSS<778>"
$PN"AL30"1;
"VSS<779>"
$PN"AL24"1;
"VSS<780>"
$PN"AL10"1;
"VSS<781>"
$PN"AL4"1;
"VSS<782>"
$PN"AK85"1;
"VSS<783>"
$PN"AK83"1;
"VSS<784>"
$PN"AK81"1;
"VSS<785>"
$PN"AK79"1;
"VSS<786>"
$PN"AK73"1;
"VSS<787>"
$PN"AK67"1;
"VSS<788>"
$PN"AK65"1;
"VSS<789>"
$PN"AK55"1;
"VSS<790>"
$PN"AK33"1;
"VSS<791>"
$PN"AK31"1;
"VSS<792>"
$PN"AK29"1;
"VSS<793>"
$PN"AK25"1;
"VSS<794>"
$PN"AK23"1;
"VSS<795>"
$PN"AK19"1;
"VSS<796>"
$PN"AK13"1;
"VSS<797>"
$PN"AK9"1;
"VSS<798>"
$PN"AJ86"1;
"VSS<799>"
$PN"AJ82"1;
"VSS<800>"
$PN"AJ78"1;
"VSS<801>"
$PN"AJ74"1;
"VSS<802>"
$PN"AJ68"1;
"VSS<803>"
$PN"AJ66"1;
"VSS<804>"
$PN"AJ54"1;
"VSS<805>"
$PN"AJ52"1;
"VSS<806>"
$PN"AJ50"1;
"VSS<807>"
$PN"AJ48"1;
"VSS<808>"
$PN"AJ46"1;
"VSS<809>"
$PN"AJ34"1;
"VSS<810>"
$PN"AJ32"1;
"VSS<811>"
$PN"AJ28"1;
"VSS<812>"
$PN"AJ26"1;
"VSS<813>"
$PN"AJ22"1;
"VSS<814>"
$PN"AJ8"1;
"VSS<815>"
$PN"AH83"1;
"VSS<816>"
$PN"AH77"1;
"VSS<817>"
$PN"AH75"1;
"VSS<818>"
$PN"AH69"1;
"VSS<819>"
$PN"AH65"1;
"VSS<820>"
$PN"AH61"1;
"VSS<821>"
$PN"AH59"1;
"VSS<822>"
$PN"AH53"1;
"VSS<823>"
$PN"AH51"1;
"VSS<824>"
$PN"AH49"1;
"VSS<825>"
$PN"AH47"1;
"VSS<826>"
$PN"AH45"1;
"VSS<827>"
$PN"AH35"1;
"VSS<828>"
$PN"AH33"1;
"VSS<829>"
$PN"AH27"1;
"VSS<830>"
$PN"AH21"1;
"VSS<831>"
$PN"AH5"1;
"VSS<832>"
$PN"AH1"1;
"VSS<833>"
$PN"AG80"1;
"VSS<834>"
$PN"AG78"1;
"VSS<835>"
$PN"AG76"1;
"VSS<836>"
$PN"AG74"1;
"VSS<837>"
$PN"AG70"1;
"VSS<838>"
$PN"AG64"1;
"VSS<839>"
$PN"AG36"1;
"VSS<840>"
$PN"AG18"1;
"VSS<841>"
$PN"AG14"1;
"VSS<842>"
$PN"AG12"1;
"VSS<843>"
$PN"AF85"1;
"VSS<844>"
$PN"AF83"1;
"VSS<845>"
$PN"AF77"1;
"VSS<846>"
$PN"AF73"1;
"VSS<847>"
$PN"AF41"1;
"VSS<848>"
$PN"AF39"1;
"VSS<849>"
$PN"AF37"1;
"VSS<850>"
$PN"AF33"1;
"VSS<851>"
$PN"AF31"1;
"VSS<852>"
$PN"AF29"1;
"VSS<853>"
$PN"AF27"1;
"VSS<854>"
$PN"AF25"8;
"VSS<855>"
$PN"AF23"8;
"VSS<856>"
$PN"AF21"8;
"VSS<857>"
$PN"AF9"8;
"VSS<858>"
$PN"AC52"8;
"VSS<859>"
$PN"AF1"8;
"VSS<860>"
$PN"AE78"8;
"VSS<861>"
$PN"AE70"8;
"VSS<862>"
$PN"AE68"8;
"VSS<863>"
$PN"AE66"8;
"VSS<864>"
$PN"AE64"8;
"VSS<865>"
$PN"AE42"8;
"VSS<866>"
$PN"AE40"8;
"VSS<867>"
$PN"AE38"8;
"VSS<868>"
$PN"AE16"8;
"VSS<869>"
$PN"AC54"8;
"VSS<870>"
$PN"AE8"8;
"VSS<871>"
$PN"AE4"8;
"VSS<872>"
$PN"AD85"8;
"VSS<873>"
$PN"AD83"8;
"VSS<874>"
$PN"AD81"8;
"VSS<875>"
$PN"AD75"8;
"VSS<876>"
$PN"AD73"8;
"VSS<877>"
$PN"AD71"8;
"VSS<878>"
$PN"AD43"8;
"VSS<879>"
$PN"AD39"8;
"VSS<880>"
$PN"AD33"8;
"VSS<881>"
$PN"AD27"8;
"VSS<882>"
$PN"AD21"8;
"VSS<883>"
$PN"AD19"8;
"VSS<884>"
$PN"AD15"8;
"VSS<885>"
$PN"AD13"8;
"VSS<886>"
$PN"AD11"8;
"VSS<887>"
$PN"AD9"8;
"VSS<888>"
$PN"AD7"8;
"VSS<889>"
$PN"AD3"8;
"VSS<890>"
$PN"AC86"8;
"VSS<891>"
$PN"AC84"8;
"VSS<892>"
$PN"AC78"8;
"VSS<893>"
$PN"AC72"8;
"VSS<894>"
$PN"AC70"8;
"VSS<895>"
$PN"AC64"8;
"VSS<896>"
$PN"AC40"8;
"VSS<897>"
$PN"AC38"8;
"VSS<898>"
$PN"AC34"8;
"VSS<899>"
$PN"AC32"8;
"VSS<900>"
$PN"AC28"8;
"VSS<901>"
$PN"AC26"8;
"VSS<902>"
$PN"AC22"8;
"VSS<903>"
$PN"AC18"8;
"VSS<904>"
$PN"AB85"8;
"VSS<905>"
$PN"AB83"8;
"VSS<906>"
$PN"AB79"8;
"VSS<907>"
$PN"AB73"8;
"VSS<908>"
$PN"AB69"8;
"VSS<909>"
$PN"AB65"8;
"VSS<910>"
$PN"AB41"8;
"VSS<911>"
$PN"AB37"8;
"VSS<912>"
$PN"AB35"8;
"VSS<913>"
$PN"AB31"8;
"VSS<914>"
$PN"AB29"8;
"VSS<915>"
$PN"AB25"8;
"VSS<916>"
$PN"AB23"8;
"VSS<917>"
$PN"AB21"8;
"VSS<918>"
$PN"AB11"8;
"VSS<919>"
$PN"AB5"8;
"VSS<920>"
$PN"AB1"8;
"VSS<921>"
$PN"AA82"8;
"VSS<922>"
$PN"AA80"8;
"VSS<923>"
$PN"AA78"8;
"VSS<924>"
$PN"AA76"8;
"VSS<925>"
$PN"AA68"8;
"VSS<926>"
$PN"AA66"8;
"VSS<927>"
$PN"AA64"8;
"VSS<928>"
$PN"AA42"8;
"VSS<929>"
$PN"AA36"8;
"VSS<930>"
$PN"AA30"8;
"VSS<931>"
$PN"AA24"8;
"VSS<932>"
$PN"AA22"8;
"VSS<933>"
$PN"AA18"8;
%"SKX_EXT_B"
"26","(-1550,2575)","0","chpset_lib","I23";
;
CDS_SEC"26"
ROOM"CPU0"
CDS_LOCATION"U5D1"
SEC"26"
CDS_LIB"chpset_lib"
SEC_TYPE"BGA1"
PACK_TYPE"BGA1"
MATERIAL"IC"
PART_NUMBER"TBD"
LOCATION"U5D1";
"VSS<614>"
$PN"BG72"2;
"VSS<615>"
$PN"BG24"2;
"VSS<616>"
$PN"BG22"2;
"VSS<617>"
$PN"BG10"2;
"VSS<618>"
$PN"BG8"2;
"VSS<619>"
$PN"BG6"2;
"VSS<620>"
$PN"BF71"2;
"VSS<621>"
$PN"BF69"2;
"VSS<622>"
$PN"BF67"2;
"VSS<623>"
$PN"BF65"2;
"VSS<624>"
$PN"BF63"2;
"VSS<625>"
$PN"BF25"2;
"VSS<626>"
$PN"BF19"2;
"VSS<627>"
$PN"BF17"2;
"VSS<628>"
$PN"BF15"2;
"VSS<629>"
$PN"BF9"2;
"VSS<630>"
$PN"BE70"2;
"VSS<631>"
$PN"BE68"2;
"VSS<632>"
$PN"BE66"2;
"VSS<633>"
$PN"BE64"2;
"VSS<634>"
$PN"BE26"2;
"VSS<635>"
$PN"BE10"2;
"VSS<636>"
$PN"BE8"2;
"VSS<637>"
$PN"BE6"2;
"VSS<638>"
$PN"BE4"2;
"VSS<639>"
$PN"BD71"2;
"VSS<640>"
$PN"BD63"2;
"VSS<641>"
$PN"BD27"2;
"VSS<642>"
$PN"BD21"2;
"VSS<643>"
$PN"BD15"2;
"VSS<644>"
$PN"BD11"2;
"VSS<645>"
$PN"BD5"2;
"VSS<646>"
$PN"BC82"2;
"VSS<647>"
$PN"BC80"2;
"VSS<648>"
$PN"BC78"2;
"VSS<649>"
$PN"BC76"2;
"VSS<650>"
$PN"BC74"2;
"VSS<651>"
$PN"BC72"2;
"VSS<652>"
$PN"BC70"2;
"VSS<653>"
$PN"BC16"2;
"VSS<654>"
$PN"BC12"2;
"VSS<655>"
$PN"BC8"2;
"VSS<656>"
$PN"BC4"2;
"VSS<657>"
$PN"BB83"2;
"VSS<658>"
$PN"BB81"2;
"VSS<659>"
$PN"BB79"2;
"VSS<660>"
$PN"BB77"2;
"VSS<661>"
$PN"BB75"2;
"VSS<662>"
$PN"BB73"2;
"VSS<663>"
$PN"BB69"2;
"VSS<664>"
$PN"BB63"2;
"VSS<665>"
$PN"BB23"2;
"VSS<666>"
$PN"BB19"2;
"VSS<667>"
$PN"BA84"2;
"VSS<668>"
$PN"BA80"2;
"VSS<669>"
$PN"BA74"2;
"VSS<670>"
$PN"BA68"2;
"VSS<671>"
$PN"BA62"2;
"VSS<672>"
$PN"BA12"2;
"VSS<673>"
$PN"BA6"2;
"VSS<674>"
$PN"BA2"2;
"VSS<675>"
$PN"AY81"2;
"VSS<676>"
$PN"AY79"2;
"VSS<677>"
$PN"AY63"2;
"VSS<678>"
$PN"AY25"2;
"VSS<679>"
$PN"AY23"2;
"VSS<680>"
$PN"AY21"2;
"VSS<681>"
$PN"AY17"2;
"VSS<682>"
$PN"AY15"2;
"VSS<683>"
$PN"AY5"2;
"VSS<684>"
$PN"AW84"2;
"VSS<685>"
$PN"AW82"2;
"VSS<686>"
$PN"AW78"2;
"VSS<687>"
$PN"AW74"2;
"VSS<688>"
$PN"AW72"2;
"VSS<689>"
$PN"AW70"2;
"VSS<690>"
$PN"AW68"2;
"VSS<691>"
$PN"AW66"2;
"VSS<692>"
$PN"AW62"2;
"VSS<693>"
$PN"AW10"2;
"VSS<694>"
$PN"AW2"3;
"VSS<695>"
$PN"AV83"3;
"VSS<696>"
$PN"AV75"3;
"VSS<697>"
$PN"AV67"3;
"VSS<698>"
$PN"AV65"3;
"VSS<699>"
$PN"AV63"3;
"VSS<700>"
$PN"AV25"3;
"VSS<701>"
$PN"AV23"3;
"VSS<702>"
$PN"AV19"3;
"VSS<703>"
$PN"AV13"3;
"VSS<704>"
$PN"AV11"3;
"VSS<705>"
$PN"AV7"3;
"VSS<706>"
$PN"AV3"3;
"VSS<707>"
$PN"AV1"3;
"VSS<708>"
$PN"AU86"3;
"VSS<709>"
$PN"AU84"3;
"VSS<710>"
$PN"AU80"3;
"VSS<711>"
$PN"AU78"3;
"VSS<712>"
$PN"AU76"3;
"VSS<713>"
$PN"AU74"3;
"VSS<714>"
$PN"AU68"3;
"VSS<715>"
$PN"AU64"3;
"VSS<716>"
$PN"AU62"3;
"VSS<717>"
$PN"AU28"3;
"VSS<718>"
$PN"AU26"3;
"VSS<719>"
$PN"AU6"3;
"VSS<720>"
$PN"AU2"3;
"VSS<721>"
$PN"AT85"3;
"VSS<722>"
$PN"AT83"3;
"VSS<723>"
$PN"AT77"3;
"VSS<724>"
$PN"AT73"3;
"VSS<725>"
$PN"AT69"3;
"VSS<726>"
$PN"AT63"3;
"VSS<727>"
$PN"AT61"3;
"VSS<728>"
$PN"AT27"3;
"VSS<729>"
$PN"AT21"3;
"VSS<730>"
$PN"AT17"3;
"VSS<731>"
$PN"AT15"3;
"VSS<732>"
$PN"P63"3;
"VSS<733>"
$PN"AC48"3;
"VSS<734>"
$PN"AR78"3;
"VSS<735>"
$PN"AR72"3;
"VSS<736>"
$PN"AR60"3;
"VSS<737>"
$PN"AR30"3;
"VSS<738>"
$PN"AR24"3;
"VSS<739>"
$PN"AR10"3;
"VSS<740>"
$PN"AP85"3;
"VSS<741>"
$PN"AP83"3;
"VSS<742>"
$PN"AP81"3;
"VSS<743>"
$PN"AP75"3;
"VSS<744>"
$PN"AP73"3;
"VSS<745>"
$PN"AP69"3;
"VSS<746>"
$PN"AP67"3;
"VSS<747>"
$PN"AP65"3;
"VSS<748>"
$PN"AP63"3;
"VSS<749>"
$PN"AP59"3;
"VSS<750>"
$PN"AP31"3;
"VSS<751>"
$PN"AP19"3;
"VSS<752>"
$PN"AP13"3;
"VSS<753>"
$PN"AP9"3;
"VSS<754>"
$PN"AP5"3;
"VSS<755>"
$PN"AN78"3;
"VSS<756>"
$PN"AN58"3;
"VSS<757>"
$PN"AN28"3;
"VSS<758>"
$PN"AN6"3;
"VSS<759>"
$PN"AN2"3;
"VSS<760>"
$PN"AM83"3;
"VSS<761>"
$PN"AM79"3;
"VSS<762>"
$PN"AM73"3;
"VSS<763>"
$PN"AM69"3;
"VSS<764>"
$PN"AM63"3;
"VSS<765>"
$PN"AM57"3;
"VSS<766>"
$PN"AM31"3;
"VSS<767>"
$PN"AC50"3;
"VSS<768>"
$PN"AM1"3;
"VSS<769>"
$PN"AL86"3;
"VSS<770>"
$PN"AL82"3;
"VSS<771>"
$PN"AL80"3;
"VSS<772>"
$PN"AL78"3;
"VSS<773>"
$PN"AL76"3;
%"GND"
"1","(-7800,450)","0","mstr_symbols","I3";
;
HDL_POWER"GND"
BODY_TYPE"PLUMBING"
CDS_LIB"mstr_symbols"
SIZE"1B"
VOLTAGE"0.0V";
"A\NAC"4;
%"GND"
"1","(-5975,450)","0","mstr_symbols","I4";
;
HDL_POWER"GND"
BODY_TYPE"PLUMBING"
CDS_LIB"mstr_symbols"
SIZE"1B"
VOLTAGE"0.0V";
"A\NAC"5;
%"GND"
"1","(-6275,450)","0","mstr_symbols","I5";
;
HDL_POWER"GND"
BODY_TYPE"PLUMBING"
CDS_LIB"mstr_symbols"
SIZE"1B"
VOLTAGE"0.0V";
"A\NAC"6;
%"GND"
"1","(-4450,450)","0","mstr_symbols","I6";
;
HDL_POWER"GND"
BODY_TYPE"PLUMBING"
CDS_LIB"mstr_symbols"
SIZE"1B"
VOLTAGE"0.0V";
"A\NAC"7;
%"GND"
"1","(-4150,450)","0","mstr_symbols","I9";
;
HDL_POWER"GND"
BODY_TYPE"PLUMBING"
SIZE"1B"
CDS_LIB"mstr_symbols"
VOLTAGE"0.0V";
"A\NAC"8;
END.
